FILE_TYPE = MACRO_DRAWING;
SET COLOR_WIRE YELLOW;
SET COLOR_PROP ORANGE;
SET COLOR_DOT WHITE;
SET COLOR_ARC YELLOW;
SET COLOR_BODY GREEN;
SET COLOR_NOTE PURPLE;
SET PROP_DISPLAY VALUE;
SET PAGE_NUMBER P53;
FORCEADD GENOA_SP5..19
(-4450 4775);
FORCEPROP 1 LAST LOCATION U26
J 0
(-5245 5601);
DISPLAY 0.489362 (-5245 5601);
PAINT SKYBLUE (-5245 5601);
FORCEPROP 0 LAST $SEC 19
J 0
(-5225 5650);
DISPLAY 0.680851 (-5225 5650);
PAINT MONO (-5225 5650);
DISPLAY INVISIBLE (-5225 5650);
FORCEPROP 0 LAST CDS_SEC 19
J 0
(-5250 5650);
DISPLAY 1.021277 (-5250 5650);
DISPLAY INVISIBLE (-5250 5650);
FORCEPROP 0 LASTPIN (-5400 5125) $PN DG53
J 2
(-5410 5135);
DISPLAY 0.489362 (-5410 5135);
PAINT MONO (-5410 5135);
FORCEPROP 0 LASTPIN (-5400 5025) $PN DG50
J 2
(-5410 5035);
DISPLAY 0.489362 (-5410 5035);
PAINT MONO (-5410 5035);
FORCEPROP 0 LASTPIN (-5400 4925) $PN DG47
J 2
(-5410 4935);
DISPLAY 0.489362 (-5410 4935);
PAINT MONO (-5410 4935);
FORCEPROP 0 LASTPIN (-5400 4825) $PN DG44
J 2
(-5410 4835);
DISPLAY 0.489362 (-5410 4835);
PAINT MONO (-5410 4835);
FORCEPROP 0 LASTPIN (-5400 5175) $PN DG54
J 2
(-5410 5185);
DISPLAY 0.489362 (-5410 5185);
PAINT MONO (-5410 5185);
FORCEPROP 0 LASTPIN (-5400 5075) $PN DG51
J 2
(-5410 5085);
DISPLAY 0.489362 (-5410 5085);
PAINT MONO (-5410 5085);
FORCEPROP 0 LASTPIN (-5400 4975) $PN DG48
J 2
(-5410 4985);
DISPLAY 0.489362 (-5410 4985);
PAINT MONO (-5410 4985);
FORCEPROP 0 LASTPIN (-5400 4875) $PN DG45
J 2
(-5410 4885);
DISPLAY 0.489362 (-5410 4885);
PAINT MONO (-5410 4885);
FORCEPROP 0 LASTPIN (-3500 5125) $PN DE52
J 0
(-3490 5135);
DISPLAY 0.489362 (-3490 5135);
PAINT MONO (-3490 5135);
FORCEPROP 0 LASTPIN (-3500 5025) $PN DE49
J 0
(-3490 5035);
DISPLAY 0.489362 (-3490 5035);
PAINT MONO (-3490 5035);
FORCEPROP 0 LASTPIN (-3500 4925) $PN DE46
J 0
(-3490 4935);
DISPLAY 0.489362 (-3490 4935);
PAINT MONO (-3490 4935);
FORCEPROP 0 LASTPIN (-3500 4825) $PN DE43
J 0
(-3490 4835);
DISPLAY 0.489362 (-3490 4835);
PAINT MONO (-3490 4835);
FORCEPROP 0 LASTPIN (-3500 5175) $PN DE53
J 0
(-3490 5185);
DISPLAY 0.489362 (-3490 5185);
PAINT MONO (-3490 5185);
FORCEPROP 0 LASTPIN (-3500 5075) $PN DE50
J 0
(-3490 5085);
DISPLAY 0.489362 (-3490 5085);
PAINT MONO (-3490 5085);
FORCEPROP 0 LASTPIN (-3500 4975) $PN DE47
J 0
(-3490 4985);
DISPLAY 0.489362 (-3490 4985);
PAINT MONO (-3490 4985);
FORCEPROP 0 LASTPIN (-3500 4875) $PN DE44
J 0
(-3490 4885);
DISPLAY 0.489362 (-3490 4885);
PAINT MONO (-3490 4885);
FORCEPROP 0 LASTPIN (-5400 4375) $PN E44
J 2
(-5410 4385);
DISPLAY 0.489362 (-5410 4385);
PAINT MONO (-5410 4385);
FORCEPROP 0 LASTPIN (-5400 4275) $PN E41
J 2
(-5410 4285);
DISPLAY 0.489362 (-5410 4285);
PAINT MONO (-5410 4285);
FORCEPROP 0 LASTPIN (-5400 4425) $PN E43
J 2
(-5410 4435);
DISPLAY 0.489362 (-5410 4435);
PAINT MONO (-5410 4435);
FORCEPROP 0 LASTPIN (-5400 4325) $PN E40
J 2
(-5410 4335);
DISPLAY 0.489362 (-5410 4335);
PAINT MONO (-5410 4335);
FORCEPROP 0 LASTPIN (-3500 4375) $PN C45
J 0
(-3490 4385);
DISPLAY 0.489362 (-3490 4385);
PAINT MONO (-3490 4385);
FORCEPROP 0 LASTPIN (-3500 4275) $PN C42
J 0
(-3490 4285);
DISPLAY 0.489362 (-3490 4285);
PAINT MONO (-3490 4285);
FORCEPROP 0 LASTPIN (-3500 4425) $PN C44
J 0
(-3490 4435);
DISPLAY 0.489362 (-3490 4435);
PAINT MONO (-3490 4435);
FORCEPROP 0 LASTPIN (-3500 4325) $PN C41
J 0
(-3490 4335);
DISPLAY 0.489362 (-3490 4335);
PAINT MONO (-3490 4335);
FORCEPROP 0 LASTPIN (-5400 4675) $PN E50
J 2
(-5410 4685);
DISPLAY 0.489362 (-5410 4685);
PAINT MONO (-5410 4685);
FORCEPROP 0 LASTPIN (-5400 4575) $PN E47
J 2
(-5410 4585);
DISPLAY 0.489362 (-5410 4585);
PAINT MONO (-5410 4585);
FORCEPROP 0 LASTPIN (-5400 4725) $PN E49
J 2
(-5410 4735);
DISPLAY 0.489362 (-5410 4735);
PAINT MONO (-5410 4735);
FORCEPROP 0 LASTPIN (-5400 4625) $PN E46
J 2
(-5410 4635);
DISPLAY 0.489362 (-5410 4635);
PAINT MONO (-5410 4635);
FORCEPROP 0 LASTPIN (-3500 4675) $PN C51
J 0
(-3490 4685);
DISPLAY 0.489362 (-3490 4685);
PAINT MONO (-3490 4685);
FORCEPROP 0 LASTPIN (-3500 4575) $PN C48
J 0
(-3490 4585);
DISPLAY 0.489362 (-3490 4585);
PAINT MONO (-3490 4585);
FORCEPROP 0 LASTPIN (-3500 4725) $PN C50
J 0
(-3490 4735);
DISPLAY 0.489362 (-3490 4735);
PAINT MONO (-3490 4735);
FORCEPROP 0 LASTPIN (-3500 4625) $PN C47
J 0
(-3490 4635);
DISPLAY 0.489362 (-3490 4635);
PAINT MONO (-3490 4635);
FORCEPROP 1 LAST MATERIAL IO
J 0
(-5245 5407);
DISPLAY 0.489362 (-5245 5407);
PAINT SKYBLUE (-5245 5407);
FORCEPROP 2 LAST VALUE SOCKET6096_13568-001
J 0
(-5250 5450);
DISPLAY 0.489362 (-5250 5450);
PAINT SKYBLUE (-5250 5450);
FORCEPROP 1 LAST PART_NUMBER DGA^6000030
J 0
(-5250 5500);
DISPLAY 0.489362 (-5250 5500);
PAINT SKYBLUE (-5250 5500);
FORCEPROP 2 LAST PART_TYPE SMLF
J 0
(-5250 5550);
DISPLAY 1.021277 (-5250 5550);
FORCEPROP 2 LAST CDS_LIB pure_quanta
J 0
(-4450 4775);
DISPLAY INVISIBLE (-4450 4775);
FORCEPROP 1 LAST CDS_LMAN_SYM_OUTLINE -800,600,800,-600
J 0
(-4450 4775);
DISPLAY 0.468085 (-4450 4775);
PAINT GREEN (-4450 4775);
DISPLAY INVISIBLE (-4450 4775);
FORCEPROP 1 LAST NEEDS_NO_SIZE TRUE
J 0
(-4450 4775);
DISPLAY 0.723404 (-4450 4775);
PAINT GREEN (-4450 4775);
DISPLAY INVISIBLE (-4450 4775);
FORCEPROP 1 LAST PATH I56
J 0
(-4450 4775);
DISPLAY 0.723404 (-4450 4775);
PAINT GREEN (-4450 4775);
DISPLAY INVISIBLE (-4450 4775);
FORCEADD OFFPAGE..2
(-2350 4625);
FORCEPROP 2 LAST $XR0 26 
J 0
(-2161 4625);
DISPLAY 0.638298 (-2161 4625);
PAINT MONO (-2161 4625);
FORCEPROP 2 LAST CDS_LIB standard
J 0
(-2350 4625);
DISPLAY INVISIBLE (-2350 4625);
FORCEPROP 1 LAST OFFPAGE TRUE
J 0
(-2025 4500);
DISPLAY 0.872340 (-2025 4500);
PAINT GREEN (-2025 4500);
DISPLAY INVISIBLE (-2025 4500);
FORCEPROP 1 LAST COMMENT_BODY TRUE
J 0
(-2395 4530);
DISPLAY 0.872340 (-2395 4530);
PAINT GREEN (-2395 4530);
DISPLAY INVISIBLE (-2395 4530);
FORCEPROP 2 LAST PATH I65
J 0
(-2150 4675);
DISPLAY 1.021277 (-2150 4675);
DISPLAY INVISIBLE (-2150 4675);
FORCEADD OFFPAGE..2
(-2350 4575);
FORCEPROP 2 LAST $XR0 26 
J 0
(-2161 4575);
DISPLAY 0.638298 (-2161 4575);
PAINT MONO (-2161 4575);
FORCEPROP 2 LAST CDS_LIB standard
J 0
(-2350 4575);
DISPLAY INVISIBLE (-2350 4575);
FORCEPROP 1 LAST OFFPAGE TRUE
J 0
(-2025 4450);
DISPLAY 0.872340 (-2025 4450);
PAINT GREEN (-2025 4450);
DISPLAY INVISIBLE (-2025 4450);
FORCEPROP 1 LAST COMMENT_BODY TRUE
J 0
(-2395 4480);
DISPLAY 0.872340 (-2395 4480);
PAINT GREEN (-2395 4480);
DISPLAY INVISIBLE (-2395 4480);
FORCEPROP 2 LAST PATH I66
J 0
(-2150 4625);
DISPLAY 1.021277 (-2150 4625);
DISPLAY INVISIBLE (-2150 4625);
FORCEADD OFFPAGE..4
R 2
(-6550 4575);
FORCEPROP 2 LAST $XR0 26 
J 0
(-6801 4575);
DISPLAY 0.638298 (-6801 4575);
PAINT MONO (-6801 4575);
FORCEPROP 2 LAST CDS_LIB standard
J 0
(-6550 4575);
DISPLAY INVISIBLE (-6550 4575);
FORCEPROP 1 LAST OFFPAGE TRUE
J 2
(-6875 4450);
DISPLAY 0.872340 (-6875 4450);
PAINT GREEN (-6875 4450);
DISPLAY INVISIBLE (-6875 4450);
FORCEPROP 1 LAST COMMENT_BODY TRUE
J 2
(-6525 4475);
DISPLAY 0.872340 (-6525 4475);
PAINT GREEN (-6525 4475);
DISPLAY INVISIBLE (-6525 4475);
FORCEPROP 2 LAST PATH I79
J 0
(-6800 4625);
DISPLAY 1.021277 (-6800 4625);
DISPLAY INVISIBLE (-6800 4625);
FORCEADD OFFPAGE..4
R 2
(-6550 4625);
FORCEPROP 2 LAST $XR0 26 
J 0
(-6801 4625);
DISPLAY 0.638298 (-6801 4625);
PAINT MONO (-6801 4625);
FORCEPROP 2 LAST CDS_LIB standard
J 0
(-6550 4625);
DISPLAY INVISIBLE (-6550 4625);
FORCEPROP 1 LAST OFFPAGE TRUE
J 2
(-6875 4500);
DISPLAY 0.872340 (-6875 4500);
PAINT GREEN (-6875 4500);
DISPLAY INVISIBLE (-6875 4500);
FORCEPROP 1 LAST COMMENT_BODY TRUE
J 2
(-6525 4525);
DISPLAY 0.872340 (-6525 4525);
PAINT GREEN (-6525 4525);
DISPLAY INVISIBLE (-6525 4525);
FORCEPROP 2 LAST PATH I80
J 0
(-6800 4675);
DISPLAY 1.021277 (-6800 4675);
DISPLAY INVISIBLE (-6800 4675);
FORCEADD QUANTA_TITLE_BLOCK_C..1
(0 0);
FORCEPROP 0 LAST CDS_CON_LAST_MODIFIED Fri Mar 11 14:52:37 2022
J 0
(-1885 15);
DISPLAY INVISIBLE (-1885 15);
FORCEPROP 1 LAST CUSTOM_TXT_CDS <CON_LAST_MODIFIED>
J 0
(-1885 15);
DISPLAY 0.978723 (-1885 15);
FORCEPROP 2 LAST CUSTOM_TXT_CDS <XR_PAGE_TITLE>
J 0
(-7890 5250);
DISPLAY 0.638298 (-7890 5250);
PAINT PINK (-7890 5250);
DISPLAY INVISIBLE (-7890 5250);
FORCEPROP 1 LAST CUSTOM_TXT_CDS <NAME_2>
J 0
(-3175 50);
FORCEPROP 1 LAST CUSTOM_TXT_CDS <NAME_1>
J 0
(-3175 175);
FORCEPROP 1 LAST CUSTOM_TXT_CDS <Q_NUMBER>
J 0
(-1403 103);
DISPLAY 1.212766 (-1403 103);
FORCEPROP 1 LAST CUSTOM_TXT_CDS <Q_PROJ>
J 0
(-2382 102);
DISPLAY 1.212766 (-2382 102);
FORCEPROP 1 LAST CUSTOM_TXT_CDS <Q_REV>
J 0
(-184 103);
DISPLAY 1.212766 (-184 103);
FORCEPROP 1 LAST CUSTOM_TXT_CDS <CON_PAGE_NUM> OF <CON_TOTAL_PAGES>
J 0
(-446 18);
DISPLAY 0.978723 (-446 18);
FORCEPROP 1 LAST Q_TITLE CPU1 PCIE P4/P5/WAFL
J 0
(-9366 26);
DISPLAY 2.446809 (-9366 26);
PAINT GREEN (-9366 26);
FORCEPROP 1 LAST Q_DEPT BU9
J 1
(-3763 49);
DISPLAY 1.957447 (-3763 49);
PAINT GREEN (-3763 49);
FORCEPROP 1 LAST CDS_LMAN_SYM_OUTLINE -9475,6775,100,-125
J 0
(0 0);
DISPLAY 0.468085 (0 0);
PAINT GREEN (0 0);
DISPLAY INVISIBLE (0 0);
FORCEPROP 2 LAST CDS_LIB pure_quanta
J 0
(0 0);
DISPLAY INVISIBLE (0 0);
FORCEPROP 2 LAST PAGE_BORDER TRUE
J 0
(-7890 5250);
DISPLAY 0.638298 (-7890 5250);
PAINT PINK (-7890 5250);
DISPLAY INVISIBLE (-7890 5250);
FORCEPROP 1 LAST COMMENT_BODY TRUE
J 0
(12 -13);
DISPLAY 0.978723 (12 -13);
PAINT GREEN (12 -13);
DISPLAY INVISIBLE (12 -13);
FORCEPROP 2 LAST CDS_XR_PAGE_TITLE CR-53 : @T6G_MB_LIB.T6G(SCH_1):PAGE53
J 0
(-7890 5250);
DISPLAY 0.638298 (-7890 5250);
PAINT PINK (-7890 5250);
DISPLAY INVISIBLE (-7890 5250);
WIRE 16 -1 (-6500 4625)(-5400 4625);
FORCEPROP 2 LAST SIG_NAME WAFL_CPU0_TX0_CPU1_RX1_DP
J 0
(-6360 4635);
DISPLAY 0.489362 (-6360 4635);
WIRE 16 -1 (-6500 4575)(-5400 4575);
FORCEPROP 2 LAST SIG_NAME WAFL_CPU0_TX0_CPU1_RX1_DN
J 0
(-6360 4585);
DISPLAY 0.489362 (-6360 4585);
FORCEPROP 0 LAST $PHYS_NET_NAME P3E_M2_0_SATA_RX_DP
J 0
(-6310 4614);
DISPLAY INVISIBLE (-6310 4614);
WIRE 16 -1 (-3500 4575)(-2400 4575);
FORCEPROP 2 LAST SIG_NAME WAFL_CPU1_TX1_CPU0_RX0_DN
J 0
(-3200 4585);
DISPLAY 0.489362 (-3200 4585);
FORCEPROP 0 LAST $PHYS_NET_NAME P3E_M2_0_SATA_RX_DP
J 0
(-3310 4614);
DISPLAY INVISIBLE (-3310 4614);
WIRE 16 -1 (-3500 4625)(-2400 4625);
FORCEPROP 2 LAST SIG_NAME WAFL_CPU1_TX1_CPU0_RX0_DP
J 0
(-3200 4635);
DISPLAY 0.489362 (-3200 4635);
QUIT
